(kicad_pcb
	(version 20241229)
	(generator "pcbnew")
	(generator_version "9.0")
	(general
		(thickness 1.61)
		(legacy_teardrops no)
	)
	(paper "A3")
	(title_block
		(title "RDIMM DDR5 Tester")
		(date "2026-05-21")
		(rev "2.2.0")
		(company "Antmicro")
		(comment 9 "footprints 698-702 of 796")
	)
	(layers
		(0 "F.Cu" signal)
		(4 "In1.Cu" power)
		(6 "In2.Cu" mixed)
		(8 "In3.Cu" power)
		(10 "In4.Cu" mixed)
		(12 "In5.Cu" power)
		(14 "In6.Cu" mixed)
		(16 "In7.Cu" power)
		(18 "In8.Cu" power)
		(20 "In9.Cu" mixed)
		(22 "In10.Cu" power)
		(2 "B.Cu" signal)
		(9 "F.Adhes" user "F.Adhesive")
		(11 "B.Adhes" user "B.Adhesive")
		(13 "F.Paste" user)
		(15 "B.Paste" user)
		(5 "F.SilkS" user "F.Silkscreen")
		(7 "B.SilkS" user "B.Silkscreen")
		(1 "F.Mask" user)
		(3 "B.Mask" user)
		(17 "Dwgs.User" user "User.Drawings")
		(19 "Cmts.User" user "User.Comments")
		(21 "Eco1.User" user "User.Eco1")
		(23 "Eco2.User" user "User.Eco2")
		(25 "Edge.Cuts" user)
		(27 "Margin" user)
		(31 "F.CrtYd" user "F.Courtyard")
		(29 "B.CrtYd" user "B.Courtyard")
		(35 "F.Fab" user)
		(33 "B.Fab" user)
	)
	(footprint "antmicro-footprints:R_0402_1005Metric"
		(layer "B.Cu")
		(at 238.451999 165.225)
		(descr "Resistor SMD 0402")
		(tags "resistor SMD 0402")
		(property "Reference" "R136"
			(at 1.173001 0.475 0)
			(layer "B.SilkS")
			(effects
				(font
					(size 0.7 0.7)
					(thickness 0.15)
				)
				(justify right bottom mirror)
			)
		)
		(property "Value" "R_0R_0402"
			(at -1.011843 -1.772047 0)
			(layer "B.Fab")
			(effects
				(font
					(size 0.7 0.7)
					(thickness 0.15)
				)
				(justify right bottom mirror)
			)
		)
		(property "Datasheet" "https://industrial.panasonic.com/cdbs/www-data/pdf/RDA0000/AOA0000C301.pdf"
			(at 0 0 0)
			(layer "F.Fab")
			(hide yes)
			(effects
				(font
					(size 1.27 1.27)
					(thickness 0.15)
				)
			)
		)
		(property "MPN" "ERJ2GE0R00X"
			(at 0 0 0)
			(unlocked yes)
			(layer "B.Fab")
			(hide yes)
			(effects
				(font
					(size 1 1)
					(thickness 0.15)
				)
				(justify mirror)
			)
		)
		(property "Manufacturer" "Panasonic"
			(at 0 0 0)
			(unlocked yes)
			(layer "B.Fab")
			(hide yes)
			(effects
				(font
					(size 1 1)
					(thickness 0.15)
				)
				(justify mirror)
			)
		)
		(property "License" "Apache-2.0"
			(at 0 0 0)
			(unlocked yes)
			(layer "B.Fab")
			(hide yes)
			(effects
				(font
					(size 1 1)
					(thickness 0.15)
				)
				(justify mirror)
			)
		)
		(property "Author" "Antmicro"
			(at 0 0 0)
			(unlocked yes)
			(layer "B.Fab")
			(hide yes)
			(effects
				(font
					(size 1 1)
					(thickness 0.15)
				)
				(justify mirror)
			)
		)
		(property "Val" "0R"
			(at 0 0 0)
			(unlocked yes)
			(layer "B.Fab")
			(hide yes)
			(effects
				(font
					(size 1 1)
					(thickness 0.15)
				)
				(justify mirror)
			)
		)
		(property "Tolerance" "~"
			(at 0 0 0)
			(unlocked yes)
			(layer "B.Fab")
			(hide yes)
			(effects
				(font
					(size 1 1)
					(thickness 0.15)
				)
				(justify mirror)
			)
		)
		(property "Current" "1A"
			(at 0 0 0)
			(unlocked yes)
			(layer "B.Fab")
			(hide yes)
			(effects
				(font
					(size 1 1)
					(thickness 0.15)
				)
				(justify mirror)
			)
		)
		(sheetname "/Supply/")
		(sheetfile "supply.kicad_sch")
		(attr smd)
		(fp_rect
			(start -0.925 0.47)
			(end 0.925 -0.47)
			(stroke
				(width 0.05)
				(type default)
			)
			(fill no)
			(layer "B.CrtYd")
		)
		(fp_rect
			(start -0.5 0.25)
			(end 0.5 -0.25)
			(stroke
				(width 0.15)
				(type solid)
			)
			(fill no)
			(layer "B.Fab")
		)
		(fp_text user "Author: Antmicro"
			(at -0.95 -4.169 180)
			(layer "B.Fab")
			(effects
				(font
					(size 0.7 0.7)
					(thickness 0.15)
				)
				(justify left bottom mirror)
			)
		)
		(fp_text user "${REFERENCE}"
			(at -0.95 -3.168 180)
			(layer "B.Fab")
			(effects
				(font
					(size 0.7 0.7)
					(thickness 0.15)
				)
				(justify left bottom mirror)
			)
		)
		(fp_text user "License: Apache-2.0"
			(at -0.95 -5.169 180)
			(layer "B.Fab")
			(effects
				(font
					(size 0.7 0.7)
					(thickness 0.15)
				)
				(justify left bottom mirror)
			)
		)
		(pad "1" smd roundrect
			(at -0.48 0)
			(size 0.59 0.64)
			(layers "B.Cu" "B.Mask" "B.Paste")
			(roundrect_rratio 0.25)
			(net 183 "POWER")
			(pintype "passive")
		)
		(pad "2" smd roundrect
			(at 0.48 0)
			(size 0.59 0.64)
			(layers "B.Cu" "B.Mask" "B.Paste")
			(roundrect_rratio 0.25)
			(net 482 "PG1")
			(pintype "passive")
		)
	)
	(footprint "antmicro-footprints:C_0402_1005Metric_EIA"
		(layer "B.Cu")
		(at 190.5 160 180)
		(descr "Capacitor SMD 0402 (1005 Metric), square (rectangular) end terminal, IPC_7351 nominal, (Body size source: IPC-SM-782 page 76, https://www.pcb-3d.com/wordpress/wp-content/uploads/ipc-sm-782a_amendment_1_and_2.pdf)")
		(tags "capacitor 0402")
		(property "Reference" "C96"
			(at 30.125 9.775 0)
			(layer "B.SilkS")
			(effects
				(font
					(size 0.7 0.7)
					(thickness 0.15)
				)
				(justify left bottom mirror)
			)
		)
		(property "Value" "C_100n_0402"
			(at 0 -1.169 0)
			(layer "B.Fab")
			(effects
				(font
					(size 0.7 0.7)
					(thickness 0.15)
				)
				(justify left bottom mirror)
			)
		)
		(property "Datasheet" "https://www.murata.com/products/productdetail?partno=GRM155R61H104KE14%23"
			(at 0 0 180)
			(layer "F.Fab")
			(hide yes)
			(effects
				(font
					(size 1.27 1.27)
					(thickness 0.15)
				)
			)
		)
		(property "MPN" "GRM155R61H104KE14D"
			(at 0 0 180)
			(unlocked yes)
			(layer "B.Fab")
			(hide yes)
			(effects
				(font
					(size 1 1)
					(thickness 0.15)
				)
				(justify mirror)
			)
		)
		(property "Manufacturer" "Murata"
			(at 0 0 180)
			(unlocked yes)
			(layer "B.Fab")
			(hide yes)
			(effects
				(font
					(size 1 1)
					(thickness 0.15)
				)
				(justify mirror)
			)
		)
		(property "License" "Apache-2.0"
			(at 0 0 180)
			(unlocked yes)
			(layer "B.Fab")
			(hide yes)
			(effects
				(font
					(size 1 1)
					(thickness 0.15)
				)
				(justify mirror)
			)
		)
		(property "Author" "Antmicro"
			(at 0 0 180)
			(unlocked yes)
			(layer "B.Fab")
			(hide yes)
			(effects
				(font
					(size 1 1)
					(thickness 0.15)
				)
				(justify mirror)
			)
		)
		(property "Val" "100n"
			(at 0 0 180)
			(unlocked yes)
			(layer "B.Fab")
			(hide yes)
			(effects
				(font
					(size 1 1)
					(thickness 0.15)
				)
				(justify mirror)
			)
		)
		(property "Voltage" "50V"
			(at 0 0 180)
			(unlocked yes)
			(layer "B.Fab")
			(hide yes)
			(effects
				(font
					(size 1 1)
					(thickness 0.15)
				)
				(justify mirror)
			)
		)
		(property "Dielectric" "X5R"
			(at 0 0 180)
			(unlocked yes)
			(layer "B.Fab")
			(hide yes)
			(effects
				(font
					(size 1 1)
					(thickness 0.15)
				)
				(justify mirror)
			)
		)
		(sheetname "/FPGA power/")
		(sheetfile "fpga-power.kicad_sch")
		(attr smd)
		(fp_rect
			(start -0.95 0.45)
			(end 0.95 -0.45)
			(stroke
				(width 0.05)
				(type default)
			)
			(fill no)
			(layer "B.CrtYd")
		)
		(fp_line
			(start 0.498 0.25)
			(end 0.498 -0.248)
			(stroke
				(width 0.15)
				(type solid)
			)
			(layer "B.Fab")
		)
		(fp_line
			(start 0.498 -0.248)
			(end -0.5 -0.248)
			(stroke
				(width 0.15)
				(type solid)
			)
			(layer "B.Fab")
		)
		(fp_line
			(start -0.5 0.25)
			(end 0.498 0.25)
			(stroke
				(width 0.15)
				(type solid)
			)
			(layer "B.Fab")
		)
		(fp_line
			(start -0.5 -0.248)
			(end -0.5 0.25)
			(stroke
				(width 0.15)
				(type solid)
			)
			(layer "B.Fab")
		)
		(fp_text user "${REFERENCE}"
			(at -0.9656 -3.169 0)
			(layer "B.Fab")
			(effects
				(font
					(size 0.7 0.7)
					(thickness 0.15)
				)
				(justify left bottom mirror)
			)
		)
		(fp_text user "License: Apache-2.0"
			(at -0.9656 -4.369 0)
			(layer "B.Fab")
			(effects
				(font
					(size 0.7 0.7)
					(thickness 0.15)
				)
				(justify left bottom mirror)
			)
		)
		(fp_text user "Author: Antmicro"
			(at -0.9656 -5.569 0)
			(layer "B.Fab")
			(effects
				(font
					(size 0.7 0.7)
					(thickness 0.15)
				)
				(justify left bottom mirror)
			)
		)
		(pad "1" smd roundrect
			(at -0.5 0 90)
			(size 0.6 0.6)
			(layers "B.Cu" "B.Mask" "B.Paste")
			(roundrect_rratio 0.25)
			(net 1 "GND")
			(pintype "passive")
		)
		(pad "2" smd roundrect
			(at 0.498 0 180)
			(size 0.6 0.6)
			(layers "B.Cu" "B.Mask" "B.Paste")
			(roundrect_rratio 0.25)
			(net 573 "+1V8_MGTVCCAUX")
			(pintype "passive")
		)
	)
	(footprint "antmicro-footprints:R_0402_1005Metric"
		(layer "B.Cu")
		(at 238.424499 179.449 180)
		(descr "Resistor SMD 0402")
		(tags "resistor SMD 0402")
		(property "Reference" "R177"
			(at -3.95 -0.5 0)
			(layer "B.SilkS")
			(effects
				(font
					(size 0.7 0.7)
					(thickness 0.15)
				)
				(justify left bottom mirror)
			)
		)
		(property "Value" "R_0R_0402"
			(at -1.011843 -1.772047 0)
			(layer "B.Fab")
			(effects
				(font
					(size 0.7 0.7)
					(thickness 0.15)
				)
				(justify left bottom mirror)
			)
		)
		(property "Datasheet" "https://industrial.panasonic.com/cdbs/www-data/pdf/RDA0000/AOA0000C301.pdf"
			(at 0 0 180)
			(layer "F.Fab")
			(hide yes)
			(effects
				(font
					(size 1.27 1.27)
					(thickness 0.15)
				)
			)
		)
		(property "Manufacturer" "Panasonic"
			(at 0 0 180)
			(unlocked yes)
			(layer "B.Fab")
			(hide yes)
			(effects
				(font
					(size 1 1)
					(thickness 0.15)
				)
				(justify mirror)
			)
		)
		(property "MPN" "ERJ2GE0R00X"
			(at 0 0 180)
			(unlocked yes)
			(layer "B.Fab")
			(hide yes)
			(effects
				(font
					(size 1 1)
					(thickness 0.15)
				)
				(justify mirror)
			)
		)
		(property "Val" "0R"
			(at 0 0 180)
			(unlocked yes)
			(layer "B.Fab")
			(hide yes)
			(effects
				(font
					(size 1 1)
					(thickness 0.15)
				)
				(justify mirror)
			)
		)
		(property "License" "Apache-2.0"
			(at 0 0 180)
			(unlocked yes)
			(layer "B.Fab")
			(hide yes)
			(effects
				(font
					(size 1 1)
					(thickness 0.15)
				)
				(justify mirror)
			)
		)
		(property "Author" "Antmicro"
			(at 0 0 180)
			(unlocked yes)
			(layer "B.Fab")
			(hide yes)
			(effects
				(font
					(size 1 1)
					(thickness 0.15)
				)
				(justify mirror)
			)
		)
		(property "Tolerance" "~"
			(at 0 0 180)
			(unlocked yes)
			(layer "B.Fab")
			(hide yes)
			(effects
				(font
					(size 1 1)
					(thickness 0.15)
				)
				(justify mirror)
			)
		)
		(property "Current" "1A"
			(at 0 0 180)
			(unlocked yes)
			(layer "B.Fab")
			(hide yes)
			(effects
				(font
					(size 1 1)
					(thickness 0.15)
				)
				(justify mirror)
			)
		)
		(sheetname "/I^{2}C + I3C/")
		(sheetfile "i2c.kicad_sch")
		(attr smd exclude_from_bom dnp)
		(fp_rect
			(start -0.925 0.47)
			(end 0.925 -0.47)
			(stroke
				(width 0.05)
				(type default)
			)
			(fill no)
			(layer "B.CrtYd")
		)
		(fp_rect
			(start -0.5 0.25)
			(end 0.5 -0.25)
			(stroke
				(width 0.15)
				(type solid)
			)
			(fill no)
			(layer "B.Fab")
		)
		(fp_text user "License: Apache-2.0"
			(at -0.95 -5.169 0)
			(layer "B.Fab")
			(effects
				(font
					(size 0.7 0.7)
					(thickness 0.15)
				)
				(justify left bottom mirror)
			)
		)
		(fp_text user "${REFERENCE}"
			(at -0.95 -3.168 0)
			(layer "B.Fab")
			(effects
				(font
					(size 0.7 0.7)
					(thickness 0.15)
				)
				(justify left bottom mirror)
			)
		)
		(fp_text user "Author: Antmicro"
			(at -0.95 -4.169 0)
			(layer "B.Fab")
			(effects
				(font
					(size 0.7 0.7)
					(thickness 0.15)
				)
				(justify left bottom mirror)
			)
		)
		(pad "1" smd roundrect
			(at -0.48 0 180)
			(size 0.59 0.64)
			(layers "B.Cu" "B.Mask" "B.Paste")
			(roundrect_rratio 0.25)
			(net 749 "/I^{2}C + I3C/PWR.SCL")
			(pintype "passive")
		)
		(pad "2" smd roundrect
			(at 0.48 0 180)
			(size 0.59 0.64)
			(layers "B.Cu" "B.Mask" "B.Paste")
			(roundrect_rratio 0.25)
			(net 465 "/FPGA banks HD/FPGA_DDR.SCL")
			(pintype "passive")
		)
	)
	(footprint "antmicro-footprints:C_0603_1608Metric"
		(layer "B.Cu")
		(at 219.62 172.06 90)
		(descr "Capacitor SMD 0603")
		(tags "capacitor 0603")
		(property "Reference" "C261"
			(at -4.04 0.39 90)
			(layer "B.SilkS")
			(effects
				(font
					(size 0.7 0.7)
					(thickness 0.15)
				)
				(justify right bottom mirror)
			)
		)
		(property "Value" "C_22u_0603"
			(at -1.42757 -1.770288 90)
			(layer "B.Fab")
			(effects
				(font
					(size 0.7 0.7)
					(thickness 0.15)
				)
				(justify right bottom mirror)
			)
		)
		(property "Datasheet" "https://www.murata.com/products/productdetail?partno=GRM188R60J226MEA0%23"
			(at 0 0 90)
			(layer "F.Fab")
			(hide yes)
			(effects
				(font
					(size 1.27 1.27)
					(thickness 0.15)
				)
			)
		)
		(property "Manufacturer" "Murata"
			(at 0 0 90)
			(unlocked yes)
			(layer "B.Fab")
			(hide yes)
			(effects
				(font
					(size 1 1)
					(thickness 0.15)
				)
				(justify mirror)
			)
		)
		(property "MPN" "GRM188R60J226MEA0D"
			(at 0 0 90)
			(unlocked yes)
			(layer "B.Fab")
			(hide yes)
			(effects
				(font
					(size 1 1)
					(thickness 0.15)
				)
				(justify mirror)
			)
		)
		(property "Val" "22u"
			(at 0 0 90)
			(unlocked yes)
			(layer "B.Fab")
			(hide yes)
			(effects
				(font
					(size 1 1)
					(thickness 0.15)
				)
				(justify mirror)
			)
		)
		(property "License" "Apache-2.0"
			(at 0 0 90)
			(unlocked yes)
			(layer "B.Fab")
			(hide yes)
			(effects
				(font
					(size 1 1)
					(thickness 0.15)
				)
				(justify mirror)
			)
		)
		(property "Author" "Antmicro"
			(at 0 0 90)
			(unlocked yes)
			(layer "B.Fab")
			(hide yes)
			(effects
				(font
					(size 1 1)
					(thickness 0.15)
				)
				(justify mirror)
			)
		)
		(property "Voltage" ""
			(at 0 0 90)
			(unlocked yes)
			(layer "B.Fab")
			(hide yes)
			(effects
				(font
					(size 1 1)
					(thickness 0.15)
				)
				(justify mirror)
			)
		)
		(property "Dielectric" ""
			(at 0 0 90)
			(unlocked yes)
			(layer "B.Fab")
			(hide yes)
			(effects
				(font
					(size 1 1)
					(thickness 0.15)
				)
				(justify mirror)
			)
		)
		(sheetname "/Supply/DC-DC VCCINT/")
		(sheetfile "dc-dc-vccint.kicad_sch")
		(attr smd)
		(fp_line
			(start -0.15 -0.4)
			(end 0.15 -0.4)
			(stroke
				(width 0.15)
				(type solid)
			)
			(layer "B.SilkS")
		)
		(fp_line
			(start -0.15 0.4)
			(end 0.15 0.4)
			(stroke
				(width 0.15)
				(type solid)
			)
			(layer "B.SilkS")
		)
		(fp_rect
			(start -1.25 0.65)
			(end 1.25 -0.65)
			(stroke
				(width 0.05)
				(type solid)
			)
			(fill no)
			(layer "B.CrtYd")
		)
		(fp_rect
			(start -0.8 0.4)
			(end 0.8 -0.4)
			(stroke
				(width 0.15)
				(type solid)
			)
			(fill no)
			(layer "B.Fab")
		)
		(fp_text user "Author: Antmicro"
			(at -1.682 -4.894 270)
			(layer "B.Fab")
			(effects
				(font
					(size 0.7 0.7)
					(thickness 0.15)
				)
				(justify left bottom mirror)
			)
		)
		(fp_text user "${REFERENCE}"
			(at -1.682 -3.895 270)
			(layer "B.Fab")
			(effects
				(font
					(size 0.7 0.7)
					(thickness 0.15)
				)
				(justify left bottom mirror)
			)
		)
		(fp_text user "License: Apache-2.0"
			(at -1.682 -5.895 270)
			(layer "B.Fab")
			(effects
				(font
					(size 0.7 0.7)
					(thickness 0.15)
				)
				(justify left bottom mirror)
			)
		)
		(pad "1" smd roundrect
			(at -0.7 0 90)
			(size 0.8 1)
			(layers "B.Cu" "B.Mask" "B.Paste")
			(roundrect_rratio 0.2)
			(net 1 "GND")
			(pintype "passive")
		)
		(pad "2" smd roundrect
			(at 0.7 0 90)
			(size 0.8 1)
			(layers "B.Cu" "B.Mask" "B.Paste")
			(roundrect_rratio 0.2)
			(net 223 "/Supply/DC-DC VCCINT/0V85_REG0")
			(pintype "passive")
		)
	)
	(footprint "antmicro-footprints:R_0402_1005Metric_EIA"
		(layer "B.Cu")
		(at 195.5 154)
		(descr "Resistor SMD 0402 (1005 Metric), square (rectangular) end terminal, IPC_7351 nominal, (Body size source: IPC-SM-782 page 76, https://www.pcb-3d.com/wordpress/wp-content/uploads/ipc-sm-782a_amendment_1_and_2.pdf)")
		(tags "resistor 0402")
		(property "Reference" "R37"
			(at -29.925 -10.3 180)
			(layer "B.SilkS")
			(effects
				(font
					(size 0.7 0.7)
					(thickness 0.15)
				)
				(justify left bottom mirror)
			)
		)
		(property "Value" "R_100R_0402"
			(at 0 -1.169 180)
			(layer "B.Fab")
			(effects
				(font
					(size 0.7 0.7)
					(thickness 0.15)
				)
				(justify left bottom mirror)
			)
		)
		(property "Datasheet" "https://www.bourns.com/docs/product-datasheets/cr.pdf"
			(at 0 0 0)
			(layer "F.Fab")
			(hide yes)
			(effects
				(font
					(size 1.27 1.27)
					(thickness 0.15)
				)
			)
		)
		(property "Manufacturer" "Bourns"
			(at 0 0 0)
			(unlocked yes)
			(layer "B.Fab")
			(hide yes)
			(effects
				(font
					(size 1 1)
					(thickness 0.15)
				)
				(justify mirror)
			)
		)
		(property "MPN" "CR0402-FX-1000GLF"
			(at 0 0 0)
			(unlocked yes)
			(layer "B.Fab")
			(hide yes)
			(effects
				(font
					(size 1 1)
					(thickness 0.15)
				)
				(justify mirror)
			)
		)
		(property "Val" "100R"
			(at 0 0 0)
			(unlocked yes)
			(layer "B.Fab")
			(hide yes)
			(effects
				(font
					(size 1 1)
					(thickness 0.15)
				)
				(justify mirror)
			)
		)
		(property "License" "Apache-2.0"
			(at 0 0 0)
			(unlocked yes)
			(layer "B.Fab")
			(hide yes)
			(effects
				(font
					(size 1 1)
					(thickness 0.15)
				)
				(justify mirror)
			)
		)
		(property "Author" "Antmicro"
			(at 0 0 0)
			(unlocked yes)
			(layer "B.Fab")
			(hide yes)
			(effects
				(font
					(size 1 1)
					(thickness 0.15)
				)
				(justify mirror)
			)
		)
		(property "Tolerance" "1%"
			(at 0 0 0)
			(unlocked yes)
			(layer "B.Fab")
			(hide yes)
			(effects
				(font
					(size 1 1)
					(thickness 0.15)
				)
				(justify mirror)
			)
		)
		(sheetname "/FPGA Config/")
		(sheetfile "fpga-config.kicad_sch")
		(attr smd exclude_from_bom dnp)
		(fp_rect
			(start -0.95 0.45)
			(end 0.95 -0.45)
			(stroke
				(width 0.05)
				(type default)
			)
			(fill no)
			(layer "B.CrtYd")
		)
		(fp_line
			(start -0.5 -0.249)
			(end -0.5 0.25)
			(stroke
				(width 0.15)
				(type solid)
			)
			(layer "B.Fab")
		)
		(fp_line
			(start -0.5 0.25)
			(end 0.499 0.25)
			(stroke
				(width 0.15)
				(type solid)
			)
			(layer "B.Fab")
		)
		(fp_line
			(start 0.499 -0.249)
			(end -0.5 -0.249)
			(stroke
				(width 0.15)
				(type solid)
			)
			(layer "B.Fab")
		)
		(fp_line
			(start 0.499 0.25)
			(end 0.499 -0.249)
			(stroke
				(width 0.15)
				(type solid)
			)
			(layer "B.Fab")
		)
		(fp_text user "Author: Antmicro"
			(at -0.95 -5.569 180)
			(layer "B.Fab")
			(effects
				(font
					(size 0.7 0.7)
					(thickness 0.15)
				)
				(justify left bottom mirror)
			)
		)
		(fp_text user "License: Apache-2.0"
			(at -0.95 -4.369 180)
			(layer "B.Fab")
			(effects
				(font
					(size 0.7 0.7)
					(thickness 0.15)
				)
				(justify left bottom mirror)
			)
		)
		(fp_text user "${REFERENCE}"
			(at -0.95 -3.169 180)
			(layer "B.Fab")
			(effects
				(font
					(size 0.7 0.7)
					(thickness 0.15)
				)
				(justify left bottom mirror)
			)
		)
		(pad "1" smd roundrect
			(at -0.5 0 270)
			(size 0.6 0.6)
			(layers "B.Cu" "B.Mask" "B.Paste")
			(roundrect_rratio 0.25)
			(net 553 "+0V85")
			(pintype "passive")
		)
		(pad "2" smd roundrect
			(at 0.499 0)
			(size 0.6 0.6)
			(layers "B.Cu" "B.Mask" "B.Paste")
			(roundrect_rratio 0.25)
			(net 462 "/FPGA Config/POR_OVERRIDE")
			(pintype "passive")
		)
	)
)
